# SCM (Grand Teton) — schematic netlist excerpt (pin names and nets, part order shuffled) for the footprints in the layout excerpt that follows; sources: Cadence DE-HDL packaged netlist, KiCad conversion of 12092022_DA0F0TMDCD0_F0T_Management_Board_D_brd_V3_OCP.brd

R567  Q_RES  33.2 1% CHIP  pkg 0402LF  page 12 : A = SMB_BMC_MM7_R_SCL ; B = SMB_BMC_MM7_SCL
R417  Q_RES  1K 1% EMPTY  pkg 0402LF  page 26 : A = TMC75_A0 ; B = GND

(kicad_pcb
	(version 20260206)
	(generator "pcbnew")
	(generator_version "10.0")
	(general
		(thickness 1.6)
		(legacy_teardrops no)
	)
	(paper "A4")
	(title_block
		(title "12092022_DA0F0TMDCD0_F0T_Management_Board_D_brd_V3_OCP.brd")
		(comment 1 "Grand Teton / footprints 1074-1075 of 1440")
	)
	(layers
		(0 "F.Cu" signal "TOP")
		(4 "In1.Cu" signal "GND")
		(6 "In2.Cu" signal "IN1")
		(8 "In3.Cu" signal "GND1")
		(10 "In4.Cu" signal "IN2")
		(12 "In5.Cu" signal "VCC")
		(14 "In6.Cu" signal "VCC1")
		(16 "In7.Cu" signal "IN3")
		(18 "In8.Cu" signal "GND2")
		(20 "In9.Cu" signal "IN4")
		(22 "In10.Cu" signal "GND3")
		(2 "B.Cu" signal "BOTTOM")
		(9 "F.Adhes" user "F.Adhesive")
		(11 "B.Adhes" user "B.Adhesive")
		(13 "F.Paste" user "Package Geometry/Pastemask Top")
		(15 "B.Paste" user "Package Geometry/Pastemask Bottom")
		(5 "F.SilkS" user "Ref Des/Silkscreen Top")
		(7 "B.SilkS" user "Ref Des/Silkscreen Bottom")
		(1 "F.Mask" user "Board Geometry/Soldermask Top")
		(3 "B.Mask" user "Board Geometry/Soldermask Bottom")
		(17 "Dwgs.User" user "User.Drawings")
		(19 "Cmts.User" user "User.Comments")
		(21 "Eco1.User" user "User.Eco1")
		(23 "Eco2.User" user "User.Eco2")
		(25 "Edge.Cuts" user "Board Geometry/Outline")
		(27 "Margin" user)
		(31 "F.CrtYd" user "Package Geometry/Place Bound Top")
		(29 "B.CrtYd" user "Package Geometry/Place Bound Bottom")
		(35 "F.Fab" user "Ref Des/Assembly Top")
		(33 "B.Fab" user "Ref Des/Assembly Bottom")
	)
	(footprint ""
		(layer "B.Cu")
		(at 62.442344 -34.637726 90)
		(property "Reference" "R567"
			(at 0 0 90)
			(layer "B.SilkS")
			(hide yes)
			(effects
				(font
					(size 1.27 1.27)
				)
				(justify mirror)
			)
		)
		(property "Value" ""
			(at 0 0 90)
			(layer "B.Fab")
			(effects
				(font
					(size 1.27 1.27)
				)
				(justify mirror)
			)
		)
		(duplicate_pad_numbers_are_jumpers no)
		(fp_line
			(start 0.7874 -0.4064)
			(end -0.7874 -0.4064)
			(stroke
				(width 0.1524)
				(type default)
			)
			(layer "B.SilkS")
		)
		(fp_line
			(start -0.7874 -0.4064)
			(end -0.7874 0.4064)
			(stroke
				(width 0.1524)
				(type default)
			)
			(layer "B.SilkS")
		)
		(fp_line
			(start 0.7874 0.4064)
			(end 0.7874 -0.4064)
			(stroke
				(width 0.1524)
				(type default)
			)
			(layer "B.SilkS")
		)
		(fp_line
			(start -0.7874 0.4064)
			(end 0.7874 0.4064)
			(stroke
				(width 0.1524)
				(type default)
			)
			(layer "B.SilkS")
		)
		(fp_line
			(start 0.67945 -0.305054)
			(end 0.12065 -0.305054)
			(stroke
				(width 0.1)
				(type default)
			)
			(layer "B.Fab")
		)
		(fp_line
			(start 0.12065 -0.305054)
			(end 0.12065 -0.2794)
			(stroke
				(width 0.1)
				(type default)
			)
			(layer "B.Fab")
		)
		(fp_line
			(start -0.12065 -0.3048)
			(end -0.67945 -0.3048)
			(stroke
				(width 0.1)
				(type default)
			)
			(layer "B.Fab")
		)
		(fp_line
			(start -0.67945 -0.3048)
			(end -0.67945 0.3048)
			(stroke
				(width 0.1)
				(type default)
			)
			(layer "B.Fab")
		)
		(fp_line
			(start 0.12065 -0.2794)
			(end -0.12065 -0.2794)
			(stroke
				(width 0.1)
				(type default)
			)
			(layer "B.Fab")
		)
		(fp_line
			(start -0.12065 -0.2794)
			(end -0.12065 -0.3048)
			(stroke
				(width 0.1)
				(type default)
			)
			(layer "B.Fab")
		)
		(fp_line
			(start 0.12065 0.2794)
			(end 0.12065 0.3048)
			(stroke
				(width 0.1)
				(type default)
			)
			(layer "B.Fab")
		)
		(fp_line
			(start -0.120396 0.2794)
			(end 0.12065 0.2794)
			(stroke
				(width 0.1)
				(type default)
			)
			(layer "B.Fab")
		)
		(fp_line
			(start 0.67945 0.3048)
			(end 0.67945 -0.305054)
			(stroke
				(width 0.1)
				(type default)
			)
			(layer "B.Fab")
		)
		(fp_line
			(start 0.12065 0.3048)
			(end 0.67945 0.3048)
			(stroke
				(width 0.1)
				(type default)
			)
			(layer "B.Fab")
		)
		(fp_line
			(start -0.120396 0.3048)
			(end -0.120396 0.2794)
			(stroke
				(width 0.1)
				(type default)
			)
			(layer "B.Fab")
		)
		(fp_line
			(start -0.67945 0.3048)
			(end -0.120396 0.3048)
			(stroke
				(width 0.1)
				(type default)
			)
			(layer "B.Fab")
		)
		(pad "1" smd circle
			(at 0.40005 0 270)
			(size 0 0)
			(layers "B.Cu" "B.Mask" "B.Paste")
			(net "SMB_BMC_MM7_R_SCL")
		)
		(pad "2" smd circle
			(at -0.40005 0 270)
			(size 0 0)
			(layers "B.Cu" "B.Mask" "B.Paste")
			(net "SMB_BMC_MM7_SCL")
		)
	)
	(footprint ""
		(layer "B.Cu")
		(at 17.907 -19.431)
		(property "Reference" "R417"
			(at 0 0 0)
			(layer "B.SilkS")
			(hide yes)
			(effects
				(font
					(size 1.27 1.27)
				)
				(justify mirror)
			)
		)
		(property "Value" ""
			(at 0 0 0)
			(layer "B.Fab")
			(effects
				(font
					(size 1.27 1.27)
				)
				(justify mirror)
			)
		)
		(duplicate_pad_numbers_are_jumpers no)
		(fp_line
			(start -0.7874 -0.4064)
			(end -0.7874 0.4064)
			(stroke
				(width 0.1524)
				(type default)
			)
			(layer "B.SilkS")
		)
		(fp_line
			(start -0.7874 0.4064)
			(end 0.7874 0.4064)
			(stroke
				(width 0.1524)
				(type default)
			)
			(layer "B.SilkS")
		)
		(fp_line
			(start 0.7874 -0.4064)
			(end -0.7874 -0.4064)
			(stroke
				(width 0.1524)
				(type default)
			)
			(layer "B.SilkS")
		)
		(fp_line
			(start 0.7874 0.4064)
			(end 0.7874 -0.4064)
			(stroke
				(width 0.1524)
				(type default)
			)
			(layer "B.SilkS")
		)
		(fp_line
			(start -0.67945 -0.3048)
			(end -0.67945 0.3048)
			(stroke
				(width 0.1)
				(type default)
			)
			(layer "B.Fab")
		)
		(fp_line
			(start -0.67945 0.3048)
			(end -0.120396 0.3048)
			(stroke
				(width 0.1)
				(type default)
			)
			(layer "B.Fab")
		)
		(fp_line
			(start -0.12065 -0.3048)
			(end -0.67945 -0.3048)
			(stroke
				(width 0.1)
				(type default)
			)
			(layer "B.Fab")
		)
		(fp_line
			(start -0.12065 -0.2794)
			(end -0.12065 -0.3048)
			(stroke
				(width 0.1)
				(type default)
			)
			(layer "B.Fab")
		)
		(fp_line
			(start -0.120396 0.2794)
			(end 0.12065 0.2794)
			(stroke
				(width 0.1)
				(type default)
			)
			(layer "B.Fab")
		)
		(fp_line
			(start -0.120396 0.3048)
			(end -0.120396 0.2794)
			(stroke
				(width 0.1)
				(type default)
			)
			(layer "B.Fab")
		)
		(fp_line
			(start 0.12065 -0.305054)
			(end 0.12065 -0.2794)
			(stroke
				(width 0.1)
				(type default)
			)
			(layer "B.Fab")
		)
		(fp_line
			(start 0.12065 -0.2794)
			(end -0.12065 -0.2794)
			(stroke
				(width 0.1)
				(type default)
			)
			(layer "B.Fab")
		)
		(fp_line
			(start 0.12065 0.2794)
			(end 0.12065 0.3048)
			(stroke
				(width 0.1)
				(type default)
			)
			(layer "B.Fab")
		)
		(fp_line
			(start 0.12065 0.3048)
			(end 0.67945 0.3048)
			(stroke
				(width 0.1)
				(type default)
			)
			(layer "B.Fab")
		)
		(fp_line
			(start 0.67945 -0.305054)
			(end 0.12065 -0.305054)
			(stroke
				(width 0.1)
				(type default)
			)
			(layer "B.Fab")
		)
		(fp_line
			(start 0.67945 0.3048)
			(end 0.67945 -0.305054)
			(stroke
				(width 0.1)
				(type default)
			)
			(layer "B.Fab")
		)
		(pad "1" smd circle
			(at 0.40005 0 180)
			(size 0 0)
			(layers "B.Cu" "B.Mask" "B.Paste")
			(net "TMC75_A0")
		)
		(pad "2" smd circle
			(at -0.40005 0 180)
			(size 0 0)
			(layers "B.Cu" "B.Mask" "B.Paste")
			(net "GND")
		)
	)
)
